(kicad_pcb
	(version 20260206)
	(generator "pcbnew")
	(generator_version "10.0")
	(general
		(thickness 1.6)
		(legacy_teardrops no)
	)
	(paper "A4")
	(title_block
		(title "v1-chassis-manager — T6M_CM_d_v01_1031_1645.brd")
		(comment 1 "Open CloudServer (Microsoft) / footprints 888-896 of 2512")
	)
	(layers
		(0 "F.Cu" signal "TOP")
		(4 "In1.Cu" signal "GND1")
		(6 "In2.Cu" signal "IN1")
		(8 "In3.Cu" signal "VCC1")
		(10 "In4.Cu" signal "VCC2")
		(12 "In5.Cu" signal "GND2")
		(14 "In6.Cu" signal "IN2")
		(16 "In7.Cu" signal "IN3")
		(18 "In8.Cu" signal "GND3")
		(2 "B.Cu" signal "BOTTOM")
		(9 "F.Adhes" user "F.Adhesive")
		(11 "B.Adhes" user "B.Adhesive")
		(13 "F.Paste" user "Package Geometry/Pastemask Top")
		(15 "B.Paste" user "Package Geometry/Pastemask Bottom")
		(5 "F.SilkS" user "Ref Des/Silkscreen Top")
		(7 "B.SilkS" user "Ref Des/Silkscreen Bottom")
		(1 "F.Mask" user "Board Geometry/Soldermask Top")
		(3 "B.Mask" user "Board Geometry/Soldermask Bottom")
		(17 "Dwgs.User" user "User.Drawings")
		(19 "Cmts.User" user "User.Comments")
		(21 "Eco1.User" user "User.Eco1")
		(23 "Eco2.User" user "User.Eco2")
		(25 "Edge.Cuts" user "Board Geometry/Outline")
		(27 "Margin" user)
		(31 "F.CrtYd" user "Package Geometry/Place Bound Top")
		(29 "B.CrtYd" user "Package Geometry/Place Bound Bottom")
		(35 "F.Fab" user "Ref Des/Assembly Top")
		(33 "B.Fab" user "Ref Des/Assembly Bottom")
	)
	(footprint ""
		(layer "F.Cu")
		(at 64.441324 -98.542856)
		(property "Reference" "C825"
			(at 27.668982 53.292502 0)
			(unlocked yes)
			(layer "F.SilkS")
			(effects
				(font
					(size 0.7874 0.5842)
					(thickness 0.1524)
				)
			)
		)
		(property "Value" ""
			(at 0 0 0)
			(layer "F.Fab")
			(effects
				(font
					(size 1.27 1.27)
				)
			)
		)
		(duplicate_pad_numbers_are_jumpers no)
		(fp_line
			(start -1.2954 -0.5842)
			(end 1.2954 -0.5842)
			(stroke
				(width 0.1524)
				(type default)
			)
			(layer "F.SilkS")
		)
		(fp_line
			(start -1.2954 0.5842)
			(end -1.2954 -0.5842)
			(stroke
				(width 0.1524)
				(type default)
			)
			(layer "F.SilkS")
		)
		(fp_line
			(start 0 -0.5842)
			(end 0 0.5842)
			(stroke
				(width 0.1524)
				(type default)
			)
			(layer "F.SilkS")
		)
		(fp_line
			(start 1.2954 -0.5842)
			(end 1.2954 0.5842)
			(stroke
				(width 0.1524)
				(type default)
			)
			(layer "F.SilkS")
		)
		(fp_line
			(start 1.2954 0.5842)
			(end -1.2954 0.5842)
			(stroke
				(width 0.1524)
				(type default)
			)
			(layer "F.SilkS")
		)
		(fp_poly
			(pts
				(xy 0.8636 -0.4572) (xy 0.8636 -0.3556) (xy 1.143 -0.3556) (xy 1.143 0.3556) (xy 0.8636 0.3556)
				(xy 0.8636 0.4572) (xy -0.8636 0.4572) (xy -0.8636 0.3556) (xy -1.143 0.3556) (xy -1.143 -0.3556)
				(xy -0.8636 -0.3556) (xy -0.8636 -0.4572)
			)
			(stroke
				(width 0)
				(type default)
			)
			(fill no)
			(layer "F.CrtYd")
		)
		(fp_line
			(start -0.884936 -0.504952)
			(end 0.884936 -0.504952)
			(stroke
				(width 0.1)
				(type default)
			)
			(layer "F.Fab")
		)
		(fp_line
			(start -0.884936 0.504952)
			(end -0.884936 -0.504952)
			(stroke
				(width 0.1)
				(type default)
			)
			(layer "F.Fab")
		)
		(fp_line
			(start 0.884936 -0.504952)
			(end 0.884936 0.504952)
			(stroke
				(width 0.1)
				(type default)
			)
			(layer "F.Fab")
		)
		(fp_line
			(start 0.884936 0.504952)
			(end -0.884936 0.504952)
			(stroke
				(width 0.1)
				(type default)
			)
			(layer "F.Fab")
		)
		(pad "1" smd rect
			(at 0.7366 0 90)
			(size 0.7112 0.8128)
			(layers "F.Cu" "F.Mask" "F.Paste")
			(net "FM_CPLD_NODE1_P1V8_SUS_EN_LV")
		)
		(pad "2" smd rect
			(at -0.7366 0 90)
			(size 0.7112 0.8128)
			(layers "F.Cu" "F.Mask" "F.Paste")
			(net "P1V8_SUS_NODE1")
		)
	)
	(footprint ""
		(layer "F.Cu")
		(at 95.627444 -118.63705 180)
		(property "Reference" "R1258"
			(at 1.326388 -1.22047 0)
			(unlocked yes)
			(layer "F.SilkS")
			(effects
				(font
					(size 0.7874 0.5842)
					(thickness 0.1524)
				)
				(justify left)
			)
		)
		(property "Value" ""
			(at 0 0 180)
			(layer "F.Fab")
			(effects
				(font
					(size 1.27 1.27)
				)
			)
		)
		(duplicate_pad_numbers_are_jumpers no)
		(fp_line
			(start 0.7874 0.4064)
			(end -0.7874 0.4064)
			(stroke
				(width 0.1524)
				(type default)
			)
			(layer "F.SilkS")
		)
		(fp_line
			(start 0.7874 -0.4064)
			(end 0.7874 0.4064)
			(stroke
				(width 0.1524)
				(type default)
			)
			(layer "F.SilkS")
		)
		(fp_line
			(start -0.7874 0.4064)
			(end -0.7874 -0.4064)
			(stroke
				(width 0.1524)
				(type default)
			)
			(layer "F.SilkS")
		)
		(fp_line
			(start -0.7874 -0.4064)
			(end 0.7874 -0.4064)
			(stroke
				(width 0.1524)
				(type default)
			)
			(layer "F.SilkS")
		)
		(fp_poly
			(pts
				(xy -0.508 0.2794) (xy -0.508 0.2286) (xy -0.635 0.2286) (xy -0.635 -0.254) (xy -0.5334 -0.254)
				(xy -0.5334 -0.2794) (xy 0.5334 -0.2794) (xy 0.5334 -0.254) (xy 0.635 -0.254) (xy 0.635 0.254) (xy 0.5334 0.254)
				(xy 0.5334 0.2794)
			)
			(stroke
				(width 0)
				(type default)
			)
			(fill no)
			(layer "F.CrtYd")
		)
		(pad "1" smd rect
			(at 0.40005 0 180)
			(size 0.4572 0.508)
			(layers "F.Cu" "F.Mask" "F.Paste")
			(net "PORT80_LOUT5")
		)
		(pad "2" smd rect
			(at -0.40005 0 180)
			(size 0.4572 0.508)
			(layers "F.Cu" "F.Mask" "F.Paste")
			(net "N53313558")
		)
	)
	(footprint ""
		(layer "F.Cu")
		(at 135.798052 -154.81935 90)
		(property "Reference" "R231"
			(at -110.78337 -60.386722 90)
			(unlocked yes)
			(layer "F.SilkS")
			(effects
				(font
					(size 0.7874 0.5842)
					(thickness 0.1524)
				)
				(justify left)
			)
		)
		(property "Value" ""
			(at 0 0 90)
			(layer "F.Fab")
			(effects
				(font
					(size 1.27 1.27)
				)
			)
		)
		(duplicate_pad_numbers_are_jumpers no)
		(fp_line
			(start 0.7874 -0.4064)
			(end 0.7874 0.4064)
			(stroke
				(width 0.1524)
				(type default)
			)
			(layer "F.SilkS")
		)
		(fp_line
			(start -0.7874 -0.4064)
			(end 0.7874 -0.4064)
			(stroke
				(width 0.1524)
				(type default)
			)
			(layer "F.SilkS")
		)
		(fp_line
			(start 0.7874 0.4064)
			(end -0.7874 0.4064)
			(stroke
				(width 0.1524)
				(type default)
			)
			(layer "F.SilkS")
		)
		(fp_line
			(start -0.7874 0.4064)
			(end -0.7874 -0.4064)
			(stroke
				(width 0.1524)
				(type default)
			)
			(layer "F.SilkS")
		)
		(fp_poly
			(pts
				(xy -0.508 0.2794) (xy -0.508 0.2286) (xy -0.635 0.2286) (xy -0.635 -0.254) (xy -0.5334 -0.254)
				(xy -0.5334 -0.2794) (xy 0.5334 -0.2794) (xy 0.5334 -0.254) (xy 0.635 -0.254) (xy 0.635 0.254) (xy 0.5334 0.254)
				(xy 0.5334 0.2794)
			)
			(stroke
				(width 0)
				(type default)
			)
			(fill no)
			(layer "F.CrtYd")
		)
		(pad "1" smd rect
			(at 0.40005 0 90)
			(size 0.4572 0.508)
			(layers "F.Cu" "F.Mask" "F.Paste")
			(net "FM_CPLD_PCIE_SW_PERST_L")
		)
		(pad "2" smd rect
			(at -0.40005 0 90)
			(size 0.4572 0.508)
			(layers "F.Cu" "F.Mask" "F.Paste")
			(net "PCIE_SW_RST_N")
		)
	)
	(footprint ""
		(layer "F.Cu")
		(at 57.488074 -6.726682)
		(property "Reference" "PC80"
			(at -2.040382 5.12318 0)
			(unlocked yes)
			(layer "F.SilkS")
			(effects
				(font
					(size 0.7874 0.5842)
					(thickness 0.1524)
				)
				(justify left)
			)
		)
		(property "Value" ""
			(at 0 0 0)
			(layer "F.Fab")
			(effects
				(font
					(size 1.27 1.27)
				)
			)
		)
		(duplicate_pad_numbers_are_jumpers no)
		(fp_line
			(start -2.249932 -4.533392)
			(end 2.249932 -4.533392)
			(stroke
				(width 0.1524)
				(type default)
			)
			(layer "F.SilkS")
		)
		(fp_line
			(start -2.249932 4.533392)
			(end -2.249932 -4.533392)
			(stroke
				(width 0.1524)
				(type default)
			)
			(layer "F.SilkS")
		)
		(fp_line
			(start 2.249932 -4.533392)
			(end 2.249932 4.533392)
			(stroke
				(width 0.1524)
				(type default)
			)
			(layer "F.SilkS")
		)
		(fp_line
			(start 2.249932 4.533392)
			(end -2.249932 4.533392)
			(stroke
				(width 0.1524)
				(type default)
			)
			(layer "F.SilkS")
		)
		(fp_poly
			(pts
				(xy 2.326132 -4.533392) (xy 2.326132 -5.39242) (xy -2.326132 -5.39242) (xy -2.326132 -4.533392)
			)
			(stroke
				(width 0)
				(type default)
			)
			(fill yes)
			(layer "F.SilkS")
		)
		(fp_poly
			(pts
				(xy -1.4605 4.457192) (xy -1.4605 3.750056) (xy -2.249932 3.750056) (xy -2.249932 -3.750056) (xy -1.4605 -3.750056)
				(xy -1.4605 -4.457192) (xy 1.4605 -4.457192) (xy 1.4605 -3.750056) (xy 2.249932 -3.750056) (xy 2.249932 3.750056)
				(xy 1.4605 3.750056) (xy 1.4605 4.457192)
			)
			(stroke
				(width 0)
				(type default)
			)
			(fill no)
			(layer "F.CrtYd")
		)
		(fp_line
			(start -2.249932 -3.750056)
			(end 2.249932 -3.750056)
			(stroke
				(width 0.1)
				(type default)
			)
			(layer "F.Fab")
		)
		(fp_line
			(start -2.249932 3.750056)
			(end -2.249932 -3.750056)
			(stroke
				(width 0.1)
				(type default)
			)
			(layer "F.Fab")
		)
		(fp_line
			(start 2.249932 -3.750056)
			(end 2.249932 3.750056)
			(stroke
				(width 0.1)
				(type default)
			)
			(layer "F.Fab")
		)
		(fp_line
			(start 2.249932 3.750056)
			(end -2.249932 3.750056)
			(stroke
				(width 0.1)
				(type default)
			)
			(layer "F.Fab")
		)
		(fp_text user "+"
			(at -2.463292 -5.479542 90)
			(unlocked yes)
			(layer "F.SilkS")
			(effects
				(font
					(size 1.6002 1.1938)
					(thickness 0.1524)
				)
				(justify left)
			)
		)
		(fp_text user "+"
			(at -0.786384 -6.322314 0)
			(unlocked yes)
			(layer "F.Fab")
			(effects
				(font
					(size 1.905 1.4224)
					(thickness 0.000001)
				)
				(justify left)
			)
		)
		(pad "1" smd rect
			(at 0 -3.199892 270)
			(size 2.413 2.8194)
			(layers "F.Cu" "F.Mask" "F.Paste")
			(net "PV_VDDR_NODE1")
		)
		(pad "2" smd rect
			(at 0 3.199892 270)
			(size 2.413 2.8194)
			(layers "F.Cu" "F.Mask" "F.Paste")
			(net "GND")
		)
	)
	(footprint ""
		(layer "F.Cu")
		(at 19.943826 -101.069902 180)
		(property "Reference" "R187"
			(at 5.197856 0.500888 0)
			(unlocked yes)
			(layer "F.SilkS")
			(effects
				(font
					(size 0.7874 0.5842)
					(thickness 0.1524)
				)
				(justify left)
			)
		)
		(property "Value" ""
			(at 0 0 180)
			(layer "F.Fab")
			(effects
				(font
					(size 1.27 1.27)
				)
			)
		)
		(duplicate_pad_numbers_are_jumpers no)
		(fp_line
			(start 0.7874 0.4064)
			(end -0.7874 0.4064)
			(stroke
				(width 0.1524)
				(type default)
			)
			(layer "F.SilkS")
		)
		(fp_line
			(start 0.7874 -0.4064)
			(end 0.7874 0.4064)
			(stroke
				(width 0.1524)
				(type default)
			)
			(layer "F.SilkS")
		)
		(fp_line
			(start -0.7874 0.4064)
			(end -0.7874 -0.4064)
			(stroke
				(width 0.1524)
				(type default)
			)
			(layer "F.SilkS")
		)
		(fp_line
			(start -0.7874 -0.4064)
			(end 0.7874 -0.4064)
			(stroke
				(width 0.1524)
				(type default)
			)
			(layer "F.SilkS")
		)
		(fp_poly
			(pts
				(xy -0.508 0.2794) (xy -0.508 0.2286) (xy -0.635 0.2286) (xy -0.635 -0.254) (xy -0.5334 -0.254)
				(xy -0.5334 -0.2794) (xy 0.5334 -0.2794) (xy 0.5334 -0.254) (xy 0.635 -0.254) (xy 0.635 0.254) (xy 0.5334 0.254)
				(xy 0.5334 0.2794)
			)
			(stroke
				(width 0)
				(type default)
			)
			(fill no)
			(layer "F.CrtYd")
		)
		(pad "1" smd rect
			(at 0.40005 0 180)
			(size 0.4572 0.508)
			(layers "F.Cu" "F.Mask" "F.Paste")
			(net "P3V3_NODE1")
		)
		(pad "2" smd rect
			(at -0.40005 0 180)
			(size 0.4572 0.508)
			(layers "F.Cu" "F.Mask" "F.Paste")
			(net "FRU_SYS_A2")
		)
	)
	(footprint ""
		(layer "F.Cu")
		(at 88.438228 -133.213094 -90)
		(property "Reference" "D36"
			(at -3.582162 -1.214374 90)
			(unlocked yes)
			(layer "F.SilkS")
			(effects
				(font
					(size 0.7874 0.5842)
					(thickness 0.1524)
				)
				(justify left)
			)
		)
		(property "Value" ""
			(at 0 0 270)
			(layer "F.Fab")
			(effects
				(font
					(size 1.27 1.27)
				)
			)
		)
		(duplicate_pad_numbers_are_jumpers no)
		(fp_line
			(start -1.3208 0.5588)
			(end -1.3208 -0.5588)
			(stroke
				(width 0.1524)
				(type default)
			)
			(layer "F.SilkS")
		)
		(fp_line
			(start 1.3208 0.5588)
			(end -1.3208 0.5588)
			(stroke
				(width 0.1524)
				(type default)
			)
			(layer "F.SilkS")
		)
		(fp_line
			(start 1.6256 0.5588)
			(end 1.6256 -0.5588)
			(stroke
				(width 0.1524)
				(type default)
			)
			(layer "F.SilkS")
		)
		(fp_line
			(start 1.778 0.5588)
			(end 1.3208 0.5588)
			(stroke
				(width 0.1524)
				(type default)
			)
			(layer "F.SilkS")
		)
		(fp_line
			(start -1.3208 -0.5588)
			(end 1.3208 -0.5588)
			(stroke
				(width 0.1524)
				(type default)
			)
			(layer "F.SilkS")
		)
		(fp_line
			(start 1.3208 -0.5588)
			(end 1.3208 0.5588)
			(stroke
				(width 0.1524)
				(type default)
			)
			(layer "F.SilkS")
		)
		(fp_line
			(start 1.4732 -0.5588)
			(end 1.4732 0.5588)
			(stroke
				(width 0.1524)
				(type default)
			)
			(layer "F.SilkS")
		)
		(fp_line
			(start 1.778 -0.5588)
			(end 1.778 0.5588)
			(stroke
				(width 0.1524)
				(type default)
			)
			(layer "F.SilkS")
		)
		(fp_line
			(start 1.778 -0.5588)
			(end 1.3208 -0.5588)
			(stroke
				(width 0.1524)
				(type default)
			)
			(layer "F.SilkS")
		)
		(fp_circle
			(center 2.453894 0.218948)
			(end 2.453894 -0.194564)
			(stroke
				(width 0.1524)
				(type default)
			)
			(fill no)
			(layer "F.SilkS")
		)
		(fp_rect
			(start -1.1684 0.508)
			(end 1.1684 -0.508)
			(stroke
				(width 0)
				(type default)
			)
			(fill no)
			(layer "F.CrtYd")
		)
		(fp_text user "-"
			(at 2.670048 0.70866 270)
			(unlocked yes)
			(layer "F.SilkS")
			(effects
				(font
					(size 0.7874 0.5842)
					(thickness 0.1524)
				)
				(justify left)
			)
		)
		(pad "A" smd rect
			(at -0.750062 0 270)
			(size 0.8128 0.8128)
			(layers "F.Cu" "F.Mask" "F.Paste")
			(net "P3V3_NODE1")
		)
		(pad "C" smd rect
			(at 0.750062 0 270)
			(size 0.8128 0.8128)
			(layers "F.Cu" "F.Mask" "F.Paste")
			(net "N53313558")
		)
	)
	(footprint ""
		(layer "F.Cu")
		(at 100.628196 -158.523686)
		(property "Reference" "PC30"
			(at 86.996016 70.784974 0)
			(unlocked yes)
			(layer "F.SilkS")
			(effects
				(font
					(size 0.7874 0.5842)
					(thickness 0.1524)
				)
				(justify left)
			)
		)
		(property "Value" ""
			(at 0 0 0)
			(layer "F.Fab")
			(effects
				(font
					(size 1.27 1.27)
				)
			)
		)
		(duplicate_pad_numbers_are_jumpers no)
		(fp_line
			(start -0.7874 -0.4064)
			(end 0.7874 -0.4064)
			(stroke
				(width 0.1524)
				(type default)
			)
			(layer "F.SilkS")
		)
		(fp_line
			(start -0.7874 0.4064)
			(end -0.7874 -0.4064)
			(stroke
				(width 0.1524)
				(type default)
			)
			(layer "F.SilkS")
		)
		(fp_line
			(start 0 0.381)
			(end 0 -0.381)
			(stroke
				(width 0.1524)
				(type default)
			)
			(layer "F.SilkS")
		)
		(fp_line
			(start 0.7874 -0.4064)
			(end 0.7874 0.4064)
			(stroke
				(width 0.1524)
				(type default)
			)
			(layer "F.SilkS")
		)
		(fp_line
			(start 0.7874 0.4064)
			(end -0.7874 0.4064)
			(stroke
				(width 0.1524)
				(type default)
			)
			(layer "F.SilkS")
		)
		(fp_poly
			(pts
				(xy -0.5334 0.254) (xy -0.635 0.254) (xy -0.635 0.2286) (xy -0.635 -0.254) (xy -0.5334 -0.254) (xy -0.5334 -0.2794)
				(xy 0.5334 -0.2794) (xy 0.5334 -0.254) (xy 0.635 -0.254) (xy 0.635 0.254) (xy 0.5334 0.254) (xy 0.5334 0.2794)
				(xy -0.508 0.2794) (xy -0.5334 0.2794)
			)
			(stroke
				(width 0)
				(type default)
			)
			(fill no)
			(layer "F.CrtYd")
		)
		(pad "1" smd rect
			(at 0.40005 0)
			(size 0.4572 0.508)
			(layers "F.Cu" "F.Mask" "F.Paste")
			(net "FM_CPLD_NODE1_P1V8_STB_EN")
		)
		(pad "2" smd rect
			(at -0.40005 0)
			(size 0.4572 0.508)
			(layers "F.Cu" "F.Mask" "F.Paste")
			(net "GND")
		)
	)
	(footprint ""
		(layer "F.Cu")
		(at 132.889752 -156.308298)
		(property "Reference" "R1284"
			(at -64.415162 110.150402 0)
			(unlocked yes)
			(layer "F.SilkS")
			(effects
				(font
					(size 0.7874 0.5842)
					(thickness 0.1524)
				)
				(justify left)
			)
		)
		(property "Value" ""
			(at 0 0 0)
			(layer "F.Fab")
			(effects
				(font
					(size 1.27 1.27)
				)
			)
		)
		(duplicate_pad_numbers_are_jumpers no)
		(fp_line
			(start -0.7874 -0.4064)
			(end 0.7874 -0.4064)
			(stroke
				(width 0.1524)
				(type default)
			)
			(layer "F.SilkS")
		)
		(fp_line
			(start -0.7874 0.4064)
			(end -0.7874 -0.4064)
			(stroke
				(width 0.1524)
				(type default)
			)
			(layer "F.SilkS")
		)
		(fp_line
			(start 0.7874 -0.4064)
			(end 0.7874 0.4064)
			(stroke
				(width 0.1524)
				(type default)
			)
			(layer "F.SilkS")
		)
		(fp_line
			(start 0.7874 0.4064)
			(end -0.7874 0.4064)
			(stroke
				(width 0.1524)
				(type default)
			)
			(layer "F.SilkS")
		)
		(fp_poly
			(pts
				(xy -0.508 0.2794) (xy -0.508 0.2286) (xy -0.635 0.2286) (xy -0.635 -0.254) (xy -0.5334 -0.254)
				(xy -0.5334 -0.2794) (xy 0.5334 -0.2794) (xy 0.5334 -0.254) (xy 0.635 -0.254) (xy 0.635 0.254) (xy 0.5334 0.254)
				(xy 0.5334 0.2794)
			)
			(stroke
				(width 0)
				(type default)
			)
			(fill no)
			(layer "F.CrtYd")
		)
		(pad "1" smd rect
			(at 0.40005 0)
			(size 0.4572 0.508)
			(layers "F.Cu" "F.Mask" "F.Paste")
			(net "P5V_NODE1")
		)
		(pad "2" smd rect
			(at -0.40005 0)
			(size 0.4572 0.508)
			(layers "F.Cu" "F.Mask" "F.Paste")
			(net "PMBUS3_EN")
		)
	)
	(footprint ""
		(layer "F.Cu")
		(at 38.250368 -6.550914 -90)
		(property "Reference" "R1123"
			(at 1.42494 9.35863 90)
			(unlocked yes)
			(layer "F.SilkS")
			(effects
				(font
					(size 0.7874 0.5842)
					(thickness 0.1524)
				)
				(justify left)
			)
		)
		(property "Value" ""
			(at 0 0 270)
			(layer "F.Fab")
			(effects
				(font
					(size 1.27 1.27)
				)
			)
		)
		(duplicate_pad_numbers_are_jumpers no)
		(fp_line
			(start -0.7874 0.4064)
			(end -0.7874 -0.4064)
			(stroke
				(width 0.1524)
				(type default)
			)
			(layer "F.SilkS")
		)
		(fp_line
			(start 0.7874 0.4064)
			(end -0.7874 0.4064)
			(stroke
				(width 0.1524)
				(type default)
			)
			(layer "F.SilkS")
		)
		(fp_line
			(start -0.7874 -0.4064)
			(end 0.7874 -0.4064)
			(stroke
				(width 0.1524)
				(type default)
			)
			(layer "F.SilkS")
		)
		(fp_line
			(start 0.7874 -0.4064)
			(end 0.7874 0.4064)
			(stroke
				(width 0.1524)
				(type default)
			)
			(layer "F.SilkS")
		)
		(fp_poly
			(pts
				(xy -0.508 0.2794) (xy -0.508 0.2286) (xy -0.635 0.2286) (xy -0.635 -0.254) (xy -0.5334 -0.254)
				(xy -0.5334 -0.2794) (xy 0.5334 -0.2794) (xy 0.5334 -0.254) (xy 0.635 -0.254) (xy 0.635 0.254) (xy 0.5334 0.254)
				(xy 0.5334 0.2794)
			)
			(stroke
				(width 0)
				(type default)
			)
			(fill no)
			(layer "F.CrtYd")
		)
		(pad "1" smd rect
			(at 0.40005 0 270)
			(size 0.4572 0.508)
			(layers "F.Cu" "F.Mask" "F.Paste")
			(net "P3V3_STB_NODE1")
		)
		(pad "2" smd rect
			(at -0.40005 0 270)
			(size 0.4572 0.508)
			(layers "F.Cu" "F.Mask" "F.Paste")
			(net "PV_VDDR_NODE1_VID0")
		)
	)
)
